(kicad_pcb
	(version 20260206)
	(generator "pcbnew")
	(generator_version "10.0")
	(general
		(thickness 1.6)
		(legacy_teardrops no)
	)
	(paper "A4")
	(title_block
		(title "03242023_DA0F0TMBIJ0_F0T_Motherboard_J_brd_V01_OCP.brd")
		(comment 1 "Grand Teton / footprints 5137-5143 of 6105")
	)
	(layers
		(0 "F.Cu" signal "TOP")
		(4 "In1.Cu" signal "GND")
		(6 "In2.Cu" signal "IN1")
		(8 "In3.Cu" signal "GND1")
		(10 "In4.Cu" signal "IN2")
		(12 "In5.Cu" signal "GND2")
		(14 "In6.Cu" signal "IN3")
		(16 "In7.Cu" signal "GND3")
		(18 "In8.Cu" signal "VCC")
		(20 "In9.Cu" signal "VCC1")
		(22 "In10.Cu" signal "GND4")
		(24 "In11.Cu" signal "IN4")
		(26 "In12.Cu" signal "GND5")
		(28 "In13.Cu" signal "IN5")
		(30 "In14.Cu" signal "GND6")
		(32 "In15.Cu" signal "IN6")
		(34 "In16.Cu" signal "GND7")
		(2 "B.Cu" signal "BOTTOM")
		(9 "F.Adhes" user "F.Adhesive")
		(11 "B.Adhes" user "B.Adhesive")
		(13 "F.Paste" user "Package Geometry/Pastemask Top")
		(15 "B.Paste" user "Package Geometry/Pastemask Bottom")
		(5 "F.SilkS" user "Ref Des/Silkscreen Top")
		(7 "B.SilkS" user "Ref Des/Silkscreen Bottom")
		(1 "F.Mask" user "Board Geometry/Soldermask Top")
		(3 "B.Mask" user "Board Geometry/Soldermask Bottom")
		(17 "Dwgs.User" user "User.Drawings")
		(19 "Cmts.User" user "User.Comments")
		(21 "Eco1.User" user "User.Eco1")
		(23 "Eco2.User" user "User.Eco2")
		(25 "Edge.Cuts" user "Board Geometry/Outline")
		(27 "Margin" user)
		(31 "F.CrtYd" user "Package Geometry/Place Bound Top")
		(29 "B.CrtYd" user "Package Geometry/Place Bound Bottom")
		(35 "F.Fab" user "Ref Des/Assembly Top")
		(33 "B.Fab" user "Ref Des/Assembly Bottom")
	)
	(footprint ""
		(layer "B.Cu")
		(at 76.89088 -11.267948 90)
		(property "Reference" "R3168"
			(at 0 0 90)
			(layer "B.SilkS")
			(hide yes)
			(effects
				(font
					(size 1.27 1.27)
				)
				(justify mirror)
			)
		)
		(property "Value" ""
			(at 0 0 90)
			(layer "B.Fab")
			(effects
				(font
					(size 1.27 1.27)
				)
				(justify mirror)
			)
		)
		(duplicate_pad_numbers_are_jumpers no)
		(fp_line
			(start 0.7874 -0.4064)
			(end -0.7874 -0.4064)
			(stroke
				(width 0.1524)
				(type default)
			)
			(layer "B.SilkS")
		)
		(fp_line
			(start -0.7874 -0.4064)
			(end -0.7874 0.4064)
			(stroke
				(width 0.1524)
				(type default)
			)
			(layer "B.SilkS")
		)
		(fp_line
			(start 0.7874 0.4064)
			(end 0.7874 -0.4064)
			(stroke
				(width 0.1524)
				(type default)
			)
			(layer "B.SilkS")
		)
		(fp_line
			(start -0.7874 0.4064)
			(end 0.7874 0.4064)
			(stroke
				(width 0.1524)
				(type default)
			)
			(layer "B.SilkS")
		)
		(fp_line
			(start 0.67945 -0.305054)
			(end 0.12065 -0.305054)
			(stroke
				(width 0.1)
				(type default)
			)
			(layer "B.Fab")
		)
		(fp_line
			(start 0.12065 -0.305054)
			(end 0.12065 -0.2794)
			(stroke
				(width 0.1)
				(type default)
			)
			(layer "B.Fab")
		)
		(fp_line
			(start -0.12065 -0.3048)
			(end -0.67945 -0.3048)
			(stroke
				(width 0.1)
				(type default)
			)
			(layer "B.Fab")
		)
		(fp_line
			(start -0.67945 -0.3048)
			(end -0.67945 0.3048)
			(stroke
				(width 0.1)
				(type default)
			)
			(layer "B.Fab")
		)
		(fp_line
			(start 0.12065 -0.2794)
			(end -0.12065 -0.2794)
			(stroke
				(width 0.1)
				(type default)
			)
			(layer "B.Fab")
		)
		(fp_line
			(start -0.12065 -0.2794)
			(end -0.12065 -0.3048)
			(stroke
				(width 0.1)
				(type default)
			)
			(layer "B.Fab")
		)
		(fp_line
			(start 0.12065 0.2794)
			(end 0.12065 0.3048)
			(stroke
				(width 0.1)
				(type default)
			)
			(layer "B.Fab")
		)
		(fp_line
			(start -0.120396 0.2794)
			(end 0.12065 0.2794)
			(stroke
				(width 0.1)
				(type default)
			)
			(layer "B.Fab")
		)
		(fp_line
			(start 0.67945 0.3048)
			(end 0.67945 -0.305054)
			(stroke
				(width 0.1)
				(type default)
			)
			(layer "B.Fab")
		)
		(fp_line
			(start 0.12065 0.3048)
			(end 0.67945 0.3048)
			(stroke
				(width 0.1)
				(type default)
			)
			(layer "B.Fab")
		)
		(fp_line
			(start -0.120396 0.3048)
			(end -0.120396 0.2794)
			(stroke
				(width 0.1)
				(type default)
			)
			(layer "B.Fab")
		)
		(fp_line
			(start -0.67945 0.3048)
			(end -0.120396 0.3048)
			(stroke
				(width 0.1)
				(type default)
			)
			(layer "B.Fab")
		)
		(pad "1" smd circle
			(at 0.40005 0 270)
			(size 0 0)
			(layers "B.Cu" "B.Mask" "B.Paste")
			(net "OCP_V3_2_MAIN_PWR_EN")
		)
		(pad "2" smd circle
			(at -0.40005 0 270)
			(size 0 0)
			(layers "B.Cu" "B.Mask" "B.Paste")
			(net "OCP_V3_2_MAIN_PWR_EN_R")
		)
	)
	(footprint ""
		(layer "B.Cu")
		(at 434.34635 -5.052568 -90)
		(property "Reference" "R435"
			(at 0 0 90)
			(layer "B.SilkS")
			(hide yes)
			(effects
				(font
					(size 1.27 1.27)
				)
				(justify mirror)
			)
		)
		(property "Value" ""
			(at 0 0 90)
			(layer "B.Fab")
			(effects
				(font
					(size 1.27 1.27)
				)
				(justify mirror)
			)
		)
		(duplicate_pad_numbers_are_jumpers no)
		(fp_line
			(start -0.7874 0.4064)
			(end 0.7874 0.4064)
			(stroke
				(width 0.1524)
				(type default)
			)
			(layer "B.SilkS")
		)
		(fp_line
			(start 0.7874 0.4064)
			(end 0.7874 -0.4064)
			(stroke
				(width 0.1524)
				(type default)
			)
			(layer "B.SilkS")
		)
		(fp_line
			(start -0.7874 -0.4064)
			(end -0.7874 0.4064)
			(stroke
				(width 0.1524)
				(type default)
			)
			(layer "B.SilkS")
		)
		(fp_line
			(start 0.7874 -0.4064)
			(end -0.7874 -0.4064)
			(stroke
				(width 0.1524)
				(type default)
			)
			(layer "B.SilkS")
		)
		(fp_line
			(start -0.67945 0.3048)
			(end -0.120396 0.3048)
			(stroke
				(width 0.1)
				(type default)
			)
			(layer "B.Fab")
		)
		(fp_line
			(start -0.120396 0.3048)
			(end -0.120396 0.2794)
			(stroke
				(width 0.1)
				(type default)
			)
			(layer "B.Fab")
		)
		(fp_line
			(start 0.12065 0.3048)
			(end 0.67945 0.3048)
			(stroke
				(width 0.1)
				(type default)
			)
			(layer "B.Fab")
		)
		(fp_line
			(start 0.67945 0.3048)
			(end 0.67945 -0.305054)
			(stroke
				(width 0.1)
				(type default)
			)
			(layer "B.Fab")
		)
		(fp_line
			(start -0.120396 0.2794)
			(end 0.12065 0.2794)
			(stroke
				(width 0.1)
				(type default)
			)
			(layer "B.Fab")
		)
		(fp_line
			(start 0.12065 0.2794)
			(end 0.12065 0.3048)
			(stroke
				(width 0.1)
				(type default)
			)
			(layer "B.Fab")
		)
		(fp_line
			(start -0.12065 -0.2794)
			(end -0.12065 -0.3048)
			(stroke
				(width 0.1)
				(type default)
			)
			(layer "B.Fab")
		)
		(fp_line
			(start 0.12065 -0.2794)
			(end -0.12065 -0.2794)
			(stroke
				(width 0.1)
				(type default)
			)
			(layer "B.Fab")
		)
		(fp_line
			(start -0.67945 -0.3048)
			(end -0.67945 0.3048)
			(stroke
				(width 0.1)
				(type default)
			)
			(layer "B.Fab")
		)
		(fp_line
			(start -0.12065 -0.3048)
			(end -0.67945 -0.3048)
			(stroke
				(width 0.1)
				(type default)
			)
			(layer "B.Fab")
		)
		(fp_line
			(start 0.12065 -0.305054)
			(end 0.12065 -0.2794)
			(stroke
				(width 0.1)
				(type default)
			)
			(layer "B.Fab")
		)
		(fp_line
			(start 0.67945 -0.305054)
			(end 0.12065 -0.305054)
			(stroke
				(width 0.1)
				(type default)
			)
			(layer "B.Fab")
		)
		(pad "1" smd circle
			(at 0.40005 0 90)
			(size 0 0)
			(layers "B.Cu" "B.Mask" "B.Paste")
			(net "RST_OCP_V3_1_BUF_N")
		)
		(pad "2" smd circle
			(at -0.40005 0 90)
			(size 0 0)
			(layers "B.Cu" "B.Mask" "B.Paste")
			(net "RST_PERST1_OCP_SFF_N")
		)
	)
	(footprint ""
		(layer "B.Cu")
		(at 132.89661 -337.145884 90)
		(property "Reference" "PC516_P1_5"
			(at 0 0 90)
			(layer "B.SilkS")
			(hide yes)
			(effects
				(font
					(size 1.27 1.27)
				)
				(justify mirror)
			)
		)
		(property "Value" ""
			(at 0 0 90)
			(layer "B.Fab")
			(effects
				(font
					(size 1.27 1.27)
				)
				(justify mirror)
			)
		)
		(duplicate_pad_numbers_are_jumpers no)
		(fp_line
			(start 1.524 -0.762)
			(end -1.524 -0.762)
			(stroke
				(width 0.1524)
				(type default)
			)
			(layer "B.SilkS")
		)
		(fp_line
			(start -1.524 -0.762)
			(end -1.524 0.762)
			(stroke
				(width 0.1524)
				(type default)
			)
			(layer "B.SilkS")
		)
		(fp_line
			(start 1.524 0.762)
			(end 1.524 -0.762)
			(stroke
				(width 0.1524)
				(type default)
			)
			(layer "B.SilkS")
		)
		(fp_line
			(start -1.524 0.762)
			(end 1.524 0.762)
			(stroke
				(width 0.1524)
				(type default)
			)
			(layer "B.SilkS")
		)
		(fp_line
			(start 1.1049 -0.724916)
			(end 1.1049 0.724916)
			(stroke
				(width 0.1)
				(type default)
			)
			(layer "B.Fab")
		)
		(fp_line
			(start -1.1049 -0.724916)
			(end 1.1049 -0.724916)
			(stroke
				(width 0.1)
				(type default)
			)
			(layer "B.Fab")
		)
		(fp_line
			(start 1.1049 0.724916)
			(end -1.1049 0.724916)
			(stroke
				(width 0.1)
				(type default)
			)
			(layer "B.Fab")
		)
		(fp_line
			(start -1.1049 0.724916)
			(end -1.1049 -0.724916)
			(stroke
				(width 0.1)
				(type default)
			)
			(layer "B.Fab")
		)
		(pad "1" smd rect
			(at 0.889 0 90)
			(size 1.016 1.27)
			(layers "B.Cu" "B.Mask" "B.Paste")
			(net "SW_P12V_PVCCIN_CPU1_FLT")
		)
		(pad "2" smd rect
			(at -0.889 0 90)
			(size 1.016 1.27)
			(layers "B.Cu" "B.Mask" "B.Paste")
			(net "GND")
		)
	)
	(footprint ""
		(layer "B.Cu")
		(at 88.837262 -329.970384 -90)
		(property "Reference" "PC189"
			(at 0 0 90)
			(layer "B.SilkS")
			(hide yes)
			(effects
				(font
					(size 1.27 1.27)
				)
				(justify mirror)
			)
		)
		(property "Value" ""
			(at 0 0 90)
			(layer "B.Fab")
			(effects
				(font
					(size 1.27 1.27)
				)
				(justify mirror)
			)
		)
		(duplicate_pad_numbers_are_jumpers no)
		(fp_line
			(start -4.533392 2.249932)
			(end 4.533392 2.249932)
			(stroke
				(width 0.1524)
				(type default)
			)
			(layer "B.SilkS")
		)
		(fp_line
			(start 4.533392 2.249932)
			(end 4.533392 -2.249932)
			(stroke
				(width 0.1524)
				(type default)
			)
			(layer "B.SilkS")
		)
		(fp_line
			(start -4.533392 -2.249932)
			(end -4.533392 2.249932)
			(stroke
				(width 0.1524)
				(type default)
			)
			(layer "B.SilkS")
		)
		(fp_line
			(start 4.533392 -2.249932)
			(end -4.533392 -2.249932)
			(stroke
				(width 0.1524)
				(type default)
			)
			(layer "B.SilkS")
		)
		(fp_rect
			(start 5.39242 2.326132)
			(end 4.533392 -2.326132)
			(stroke
				(width 0)
				(type default)
			)
			(fill yes)
			(layer "B.SilkS")
		)
		(fp_line
			(start -3.750056 2.249932)
			(end 3.750056 2.249932)
			(stroke
				(width 0.1)
				(type default)
			)
			(layer "B.Fab")
		)
		(fp_line
			(start 3.750056 2.249932)
			(end 3.750056 -2.249932)
			(stroke
				(width 0.1)
				(type default)
			)
			(layer "B.Fab")
		)
		(fp_line
			(start -3.750056 -2.249932)
			(end -3.750056 2.249932)
			(stroke
				(width 0.1)
				(type default)
			)
			(layer "B.Fab")
		)
		(fp_line
			(start 3.750056 -2.249932)
			(end -3.750056 -2.249932)
			(stroke
				(width 0.1)
				(type default)
			)
			(layer "B.Fab")
		)
		(fp_text user "-"
			(at -4.634484 0.883412 270)
			(unlocked yes)
			(layer "B.SilkS")
			(effects
				(font
					(size 1.905 1.4224)
					(thickness 0.1524)
				)
				(justify left mirror)
			)
		)
		(fp_text user "+"
			(at 6.322314 0.786384 180)
			(unlocked yes)
			(layer "B.SilkS")
			(effects
				(font
					(size 1.905 1.4224)
					(thickness 0.1524)
				)
				(justify left mirror)
			)
		)
		(fp_text user "+"
			(at 6.322314 0.786384 180)
			(unlocked yes)
			(layer "B.Fab")
			(effects
				(font
					(size 1.905 1.4224)
					(thickness 0.1524)
				)
				(justify left mirror)
			)
		)
		(fp_text user "-"
			(at -4.8514 -0.14605 270)
			(unlocked yes)
			(layer "B.Fab")
			(effects
				(font
					(size 1.905 1.4224)
					(thickness 0.1524)
				)
				(justify left mirror)
			)
		)
		(pad "1" smd rect
			(at 3.199892 0 90)
			(size 2.413 2.8194)
			(layers "B.Cu" "B.Mask" "B.Paste")
			(net "PVCCIN_CPU1")
		)
		(pad "2" smd rect
			(at -3.199892 0 90)
			(size 2.413 2.8194)
			(layers "B.Cu" "B.Mask" "B.Paste")
			(net "GND")
		)
	)
	(footprint ""
		(layer "B.Cu")
		(at 70.369684 -185.791856 90)
		(property "Reference" "R54"
			(at 0 0 90)
			(layer "B.SilkS")
			(hide yes)
			(effects
				(font
					(size 1.27 1.27)
				)
				(justify mirror)
			)
		)
		(property "Value" ""
			(at 0 0 90)
			(layer "B.Fab")
			(effects
				(font
					(size 1.27 1.27)
				)
				(justify mirror)
			)
		)
		(duplicate_pad_numbers_are_jumpers no)
		(fp_line
			(start 0.7874 -0.4064)
			(end -0.7874 -0.4064)
			(stroke
				(width 0.1524)
				(type default)
			)
			(layer "B.SilkS")
		)
		(fp_line
			(start -0.7874 -0.4064)
			(end -0.7874 0.4064)
			(stroke
				(width 0.1524)
				(type default)
			)
			(layer "B.SilkS")
		)
		(fp_line
			(start 0.7874 0.4064)
			(end 0.7874 -0.4064)
			(stroke
				(width 0.1524)
				(type default)
			)
			(layer "B.SilkS")
		)
		(fp_line
			(start -0.7874 0.4064)
			(end 0.7874 0.4064)
			(stroke
				(width 0.1524)
				(type default)
			)
			(layer "B.SilkS")
		)
		(fp_line
			(start 0.67945 -0.305054)
			(end 0.12065 -0.305054)
			(stroke
				(width 0.1)
				(type default)
			)
			(layer "B.Fab")
		)
		(fp_line
			(start 0.12065 -0.305054)
			(end 0.12065 -0.2794)
			(stroke
				(width 0.1)
				(type default)
			)
			(layer "B.Fab")
		)
		(fp_line
			(start -0.12065 -0.3048)
			(end -0.67945 -0.3048)
			(stroke
				(width 0.1)
				(type default)
			)
			(layer "B.Fab")
		)
		(fp_line
			(start -0.67945 -0.3048)
			(end -0.67945 0.3048)
			(stroke
				(width 0.1)
				(type default)
			)
			(layer "B.Fab")
		)
		(fp_line
			(start 0.12065 -0.2794)
			(end -0.12065 -0.2794)
			(stroke
				(width 0.1)
				(type default)
			)
			(layer "B.Fab")
		)
		(fp_line
			(start -0.12065 -0.2794)
			(end -0.12065 -0.3048)
			(stroke
				(width 0.1)
				(type default)
			)
			(layer "B.Fab")
		)
		(fp_line
			(start 0.12065 0.2794)
			(end 0.12065 0.3048)
			(stroke
				(width 0.1)
				(type default)
			)
			(layer "B.Fab")
		)
		(fp_line
			(start -0.120396 0.2794)
			(end 0.12065 0.2794)
			(stroke
				(width 0.1)
				(type default)
			)
			(layer "B.Fab")
		)
		(fp_line
			(start 0.67945 0.3048)
			(end 0.67945 -0.305054)
			(stroke
				(width 0.1)
				(type default)
			)
			(layer "B.Fab")
		)
		(fp_line
			(start 0.12065 0.3048)
			(end 0.67945 0.3048)
			(stroke
				(width 0.1)
				(type default)
			)
			(layer "B.Fab")
		)
		(fp_line
			(start -0.120396 0.3048)
			(end -0.120396 0.2794)
			(stroke
				(width 0.1)
				(type default)
			)
			(layer "B.Fab")
		)
		(fp_line
			(start -0.67945 0.3048)
			(end -0.120396 0.3048)
			(stroke
				(width 0.1)
				(type default)
			)
			(layer "B.Fab")
		)
		(pad "1" smd circle
			(at 0.40005 0 270)
			(size 0 0)
			(layers "B.Cu" "B.Mask" "B.Paste")
			(net "DBP_CPU1_HOOK9_MBP3_GTL_QS_R_N")
		)
		(pad "2" smd circle
			(at -0.40005 0 270)
			(size 0 0)
			(layers "B.Cu" "B.Mask" "B.Paste")
			(net "DBP_CPU_HOOK9_MBP3_GTL_QS_N")
		)
	)
	(footprint ""
		(layer "B.Cu")
		(at 335.909158 -45.129704 90)
		(property "Reference" "C1214"
			(at 0 0 90)
			(layer "B.SilkS")
			(hide yes)
			(effects
				(font
					(size 1.27 1.27)
				)
				(justify mirror)
			)
		)
		(property "Value" ""
			(at 0 0 90)
			(layer "B.Fab")
			(effects
				(font
					(size 1.27 1.27)
				)
				(justify mirror)
			)
		)
		(duplicate_pad_numbers_are_jumpers no)
		(fp_line
			(start 0.7874 -0.4064)
			(end -0.7874 -0.4064)
			(stroke
				(width 0.1524)
				(type default)
			)
			(layer "B.SilkS")
		)
		(fp_line
			(start -0.7874 -0.4064)
			(end -0.7874 0.4064)
			(stroke
				(width 0.1524)
				(type default)
			)
			(layer "B.SilkS")
		)
		(fp_line
			(start 0.7874 0.4064)
			(end 0.7874 -0.4064)
			(stroke
				(width 0.1524)
				(type default)
			)
			(layer "B.SilkS")
		)
		(fp_line
			(start -0.7874 0.4064)
			(end 0.7874 0.4064)
			(stroke
				(width 0.1524)
				(type default)
			)
			(layer "B.SilkS")
		)
		(fp_line
			(start 0.67945 -0.305054)
			(end 0.12065 -0.305054)
			(stroke
				(width 0.1)
				(type default)
			)
			(layer "B.Fab")
		)
		(fp_line
			(start 0.12065 -0.305054)
			(end 0.12065 -0.2794)
			(stroke
				(width 0.1)
				(type default)
			)
			(layer "B.Fab")
		)
		(fp_line
			(start -0.12065 -0.3048)
			(end -0.67945 -0.3048)
			(stroke
				(width 0.1)
				(type default)
			)
			(layer "B.Fab")
		)
		(fp_line
			(start -0.67945 -0.3048)
			(end -0.67945 0.3048)
			(stroke
				(width 0.1)
				(type default)
			)
			(layer "B.Fab")
		)
		(fp_line
			(start 0.12065 -0.2794)
			(end -0.12065 -0.2794)
			(stroke
				(width 0.1)
				(type default)
			)
			(layer "B.Fab")
		)
		(fp_line
			(start -0.12065 -0.2794)
			(end -0.12065 -0.3048)
			(stroke
				(width 0.1)
				(type default)
			)
			(layer "B.Fab")
		)
		(fp_line
			(start 0.12065 0.2794)
			(end 0.12065 0.3048)
			(stroke
				(width 0.1)
				(type default)
			)
			(layer "B.Fab")
		)
		(fp_line
			(start -0.120396 0.2794)
			(end 0.12065 0.2794)
			(stroke
				(width 0.1)
				(type default)
			)
			(layer "B.Fab")
		)
		(fp_line
			(start 0.67945 0.3048)
			(end 0.67945 -0.305054)
			(stroke
				(width 0.1)
				(type default)
			)
			(layer "B.Fab")
		)
		(fp_line
			(start 0.12065 0.3048)
			(end 0.67945 0.3048)
			(stroke
				(width 0.1)
				(type default)
			)
			(layer "B.Fab")
		)
		(fp_line
			(start -0.120396 0.3048)
			(end -0.120396 0.2794)
			(stroke
				(width 0.1)
				(type default)
			)
			(layer "B.Fab")
		)
		(fp_line
			(start -0.67945 0.3048)
			(end -0.120396 0.3048)
			(stroke
				(width 0.1)
				(type default)
			)
			(layer "B.Fab")
		)
		(pad "1" smd circle
			(at 0.40005 0 270)
			(size 0 0)
			(layers "B.Cu" "B.Mask" "B.Paste")
			(net "P1V05_PCH_AUX")
		)
		(pad "2" smd circle
			(at -0.40005 0 270)
			(size 0 0)
			(layers "B.Cu" "B.Mask" "B.Paste")
			(net "GND")
		)
	)
	(footprint ""
		(layer "B.Cu")
		(at 81.681574 -331.58938 -90)
		(property "Reference" "PC500_P1_7"
			(at 0 0 90)
			(layer "B.SilkS")
			(hide yes)
			(effects
				(font
					(size 1.27 1.27)
				)
				(justify mirror)
			)
		)
		(property "Value" ""
			(at 0 0 90)
			(layer "B.Fab")
			(effects
				(font
					(size 1.27 1.27)
				)
				(justify mirror)
			)
		)
		(duplicate_pad_numbers_are_jumpers no)
		(fp_line
			(start -1.524 0.762)
			(end 1.524 0.762)
			(stroke
				(width 0.1524)
				(type default)
			)
			(layer "B.SilkS")
		)
		(fp_line
			(start 1.524 0.762)
			(end 1.524 -0.762)
			(stroke
				(width 0.1524)
				(type default)
			)
			(layer "B.SilkS")
		)
		(fp_line
			(start -1.524 -0.762)
			(end -1.524 0.762)
			(stroke
				(width 0.1524)
				(type default)
			)
			(layer "B.SilkS")
		)
		(fp_line
			(start 1.524 -0.762)
			(end -1.524 -0.762)
			(stroke
				(width 0.1524)
				(type default)
			)
			(layer "B.SilkS")
		)
		(fp_line
			(start -1.1049 0.724916)
			(end -1.1049 -0.724916)
			(stroke
				(width 0.1)
				(type default)
			)
			(layer "B.Fab")
		)
		(fp_line
			(start 1.1049 0.724916)
			(end -1.1049 0.724916)
			(stroke
				(width 0.1)
				(type default)
			)
			(layer "B.Fab")
		)
		(fp_line
			(start -1.1049 -0.724916)
			(end 1.1049 -0.724916)
			(stroke
				(width 0.1)
				(type default)
			)
			(layer "B.Fab")
		)
		(fp_line
			(start 1.1049 -0.724916)
			(end 1.1049 0.724916)
			(stroke
				(width 0.1)
				(type default)
			)
			(layer "B.Fab")
		)
		(pad "1" smd rect
			(at 0.889 0 270)
			(size 1.016 1.27)
			(layers "B.Cu" "B.Mask" "B.Paste")
			(net "PVCCIN_CPU1")
		)
		(pad "2" smd rect
			(at -0.889 0 270)
			(size 1.016 1.27)
			(layers "B.Cu" "B.Mask" "B.Paste")
			(net "GND")
		)
	)
)
